# BASEBOARD_FAB2 (Tioga Pass) — schematic netlist excerpt (pin names and nets, part order shuffled) for the footprints in the layout excerpt that follows; sources: Cadence DE-HDL packaged netlist, KiCad conversion of Wiwynn_Tioga_Pass_MB.brd

C3N1  CAP_A  1.0UF 6.3V 10% X6S  pkg 0402V  page 132 : A = PVNN_PCH_STBY ; B = GND
C7W13  SC22U16V5MX-4-GP  20%  pkg SMD-BCG5  page 220 : \1\ = VR_FET_SW_P12V_STBY_PVDDQ_DEF ; \2\ = GND
C3P44  CAP_A  0.1UF 16V 10% X7R  pkg 0402V  page 192 : A = P3V3_STBY ; B = GND

(kicad_pcb
	(version 20260206)
	(generator "pcbnew")
	(generator_version "10.0")
	(general
		(thickness 1.6)
		(legacy_teardrops no)
	)
	(paper "A4")
	(title_block
		(title "Wiwynn_Tioga_Pass_MB.brd")
		(comment 1 "Tioga Pass / footprints 4324-4326 of 4770")
	)
	(layers
		(0 "F.Cu" signal "TOP")
		(4 "In1.Cu" signal "L2GND")
		(6 "In2.Cu" signal "L3")
		(8 "In3.Cu" signal "L4GND")
		(10 "In4.Cu" signal "L5")
		(12 "In5.Cu" signal "L6GND")
		(14 "In6.Cu" signal "L7VCC")
		(16 "In7.Cu" signal "L8VCC")
		(18 "In8.Cu" signal "L9GND")
		(20 "In9.Cu" signal "L10")
		(22 "In10.Cu" signal "L11GND")
		(24 "In11.Cu" signal "L12")
		(26 "In12.Cu" signal "L13GND")
		(2 "B.Cu" signal "BOTTOM")
		(9 "F.Adhes" user "F.Adhesive")
		(11 "B.Adhes" user "B.Adhesive")
		(13 "F.Paste" user "Package Geometry/Pastemask Top")
		(15 "B.Paste" user "Package Geometry/Pastemask Bottom")
		(5 "F.SilkS" user "Ref Des/Silkscreen Top")
		(7 "B.SilkS" user "Ref Des/Silkscreen Bottom")
		(1 "F.Mask" user "Board Geometry/Soldermask Top")
		(3 "B.Mask" user "Board Geometry/Soldermask Bottom")
		(17 "Dwgs.User" user "User.Drawings")
		(19 "Cmts.User" user "User.Comments")
		(21 "Eco1.User" user "User.Eco1")
		(23 "Eco2.User" user "User.Eco2")
		(25 "Edge.Cuts" user "Board Geometry/Outline")
		(27 "Margin" user)
		(31 "F.CrtYd" user "Package Geometry/Place Bound Top")
		(29 "B.CrtYd" user "Package Geometry/Place Bound Bottom")
		(35 "F.Fab" user "Ref Des/Assembly Top")
		(33 "B.Fab" user "Ref Des/Assembly Bottom")
	)
	(footprint ""
		(layer "B.Cu")
		(at 348.052136 -141.085062 -90)
		(property "Reference" "C7W13"
			(at 0 0 90)
			(layer "B.SilkS")
			(hide yes)
			(effects
				(font
					(size 1.27 1.27)
				)
				(justify mirror)
			)
		)
		(property "Value" "*"
			(at 0.0762 -6.2357 270)
			(unlocked yes)
			(layer "B.Fab")
			(hide yes)
			(effects
				(font
					(size 1.27 1.016)
					(thickness 0.1524)
				)
				(justify mirror)
			)
		)
		(property "Device Type" "SC22U16V5MX-4-GP_SMD-BCG5-SC22A"
			(at 0.0762 -8.2677 270)
			(unlocked yes)
			(layer "B.Fab")
			(hide yes)
			(effects
				(font
					(size 1.27 1.016)
					(thickness 0.1524)
				)
				(justify mirror)
			)
		)
		(duplicate_pad_numbers_are_jumpers no)
		(fp_line
			(start -0.635 0)
			(end 0.635 0)
			(stroke
				(width 0.508)
				(type default)
			)
			(layer "B.SilkS")
		)
		(fp_rect
			(start 0.9652 1.778)
			(end -0.9652 -1.778)
			(stroke
				(width 0)
				(type default)
			)
			(fill no)
			(layer "B.CrtYd")
		)
		(fp_poly
			(pts
				(xy 0.9652 -1.778) (xy -0.9652 -1.778) (xy -0.9652 1.778) (xy 0.9652 1.778)
			)
			(stroke
				(width 0)
				(type default)
			)
			(fill no)
			(layer "B.Fab")
		)
		(pad "1" smd rect
			(at 0 -0.9652 90)
			(size 1.397 1.143)
			(layers "B.Cu" "B.Mask" "B.Paste")
			(net "VR_FET_SW_P12V_STBY_PVDDQ_DEF")
		)
		(pad "2" smd rect
			(at 0 0.9652 90)
			(size 1.397 1.143)
			(layers "B.Cu" "B.Mask" "B.Paste")
			(net "GND")
		)
	)
	(footprint ""
		(layer "B.Cu")
		(at 369.945158 -77.896212 -90)
		(property "Reference" "C3P44"
			(at 0 0 90)
			(layer "B.SilkS")
			(hide yes)
			(effects
				(font
					(size 1.27 1.27)
				)
				(justify mirror)
			)
		)
		(property "Value" ""
			(at 0 0 90)
			(layer "B.Fab")
			(effects
				(font
					(size 1.27 1.27)
				)
				(justify mirror)
			)
		)
		(duplicate_pad_numbers_are_jumpers no)
		(fp_rect
			(start 0.2794 0.9144)
			(end -0.2794 -0.1143)
			(stroke
				(width 0)
				(type default)
			)
			(fill no)
			(layer "B.CrtYd")
		)
		(fp_line
			(start -0.2794 0.9144)
			(end 0.2794 0.9144)
			(stroke
				(width 0.1)
				(type default)
			)
			(layer "B.Fab")
		)
		(fp_line
			(start 0.2794 0.9144)
			(end 0.2794 -0.1143)
			(stroke
				(width 0.1)
				(type default)
			)
			(layer "B.Fab")
		)
		(fp_line
			(start -0.2794 -0.1143)
			(end -0.2794 0.9144)
			(stroke
				(width 0.1)
				(type default)
			)
			(layer "B.Fab")
		)
		(fp_line
			(start 0.2794 -0.1143)
			(end -0.2794 -0.1143)
			(stroke
				(width 0.1)
				(type default)
			)
			(layer "B.Fab")
		)
		(pad "1" smd custom
			(at 0 0 180)
			(size 0.10414 0.10414)
			(layers "B.Cu" "B.Mask" "B.Paste")
			(net "P3V3_STBY")
			(options
				(clearance outline)
				(anchor circle)
			)
			(primitives
				(gr_poly
					(pts
						(xy -0.20828 -0.08636) (xy -0.20828 0.08636) (xy -0.08636 0.20828) (xy 0.086614 0.20828) (xy 0.20828 0.086614)
						(xy 0.20828 -0.08636) (xy 0.08636 -0.20828) (xy -0.08636 -0.20828)
					)
					(width 0)
					(fill yes)
				)
			)
		)
		(pad "2" smd custom
			(at 0 0.8001 180)
			(size 0.10414 0.10414)
			(layers "B.Cu" "B.Mask" "B.Paste")
			(net "GND")
			(options
				(clearance outline)
				(anchor circle)
			)
			(primitives
				(gr_poly
					(pts
						(xy -0.20828 -0.08636) (xy -0.20828 0.08636) (xy -0.08636 0.20828) (xy 0.086614 0.20828) (xy 0.20828 0.086614)
						(xy 0.20828 -0.08636) (xy 0.08636 -0.20828) (xy -0.08636 -0.20828)
					)
					(width 0)
					(fill yes)
				)
			)
		)
		(zone
			(layer "B.Cu")
			(hatch none 0.5)
			(connect_pads
				(clearance 0)
			)
			(min_thickness 0.25)
			(keepout
				(tracks allowed)
				(vias not_allowed)
				(pads allowed)
				(copperpour not_allowed)
				(footprints allowed)
			)
			(placement
				(enabled no)
				(sheetname "")
			)
			(fill
				(thermal_gap 0.5)
				(thermal_bridge_width 0.5)
				(island_removal_mode 0)
			)
			(polygon
				(pts
					(xy 369.735608 -77.808582) (xy 369.354608 -77.808582) (xy 369.354608 -77.983842) (xy 369.735608 -77.984096)
				)
			)
		)
		(zone
			(layer "B.Cu")
			(hatch none 0.5)
			(connect_pads
				(clearance 0)
			)
			(min_thickness 0.25)
			(keepout
				(tracks not_allowed)
				(vias allowed)
				(pads allowed)
				(copperpour not_allowed)
				(footprints allowed)
			)
			(placement
				(enabled no)
				(sheetname "")
			)
			(fill
				(thermal_gap 0.5)
				(thermal_bridge_width 0.5)
				(island_removal_mode 0)
			)
			(polygon
				(pts
					(xy 369.735608 -77.808582) (xy 369.354608 -77.808582) (xy 369.354608 -77.983842) (xy 369.735608 -77.984096)
				)
			)
		)
	)
	(footprint ""
		(layer "B.Cu")
		(at 385.33705 -111.85525 180)
		(property "Reference" "C3N1"
			(at 0 0 0)
			(layer "B.SilkS")
			(hide yes)
			(effects
				(font
					(size 1.27 1.27)
				)
				(justify mirror)
			)
		)
		(property "Value" ""
			(at 0 0 0)
			(layer "B.Fab")
			(effects
				(font
					(size 1.27 1.27)
				)
				(justify mirror)
			)
		)
		(duplicate_pad_numbers_are_jumpers no)
		(fp_rect
			(start 0.2794 0.9144)
			(end -0.2794 -0.1143)
			(stroke
				(width 0)
				(type default)
			)
			(fill no)
			(layer "B.CrtYd")
		)
		(fp_line
			(start 0.2794 0.9144)
			(end 0.2794 -0.1143)
			(stroke
				(width 0.1)
				(type default)
			)
			(layer "B.Fab")
		)
		(fp_line
			(start 0.2794 -0.1143)
			(end -0.2794 -0.1143)
			(stroke
				(width 0.1)
				(type default)
			)
			(layer "B.Fab")
		)
		(fp_line
			(start -0.2794 0.9144)
			(end 0.2794 0.9144)
			(stroke
				(width 0.1)
				(type default)
			)
			(layer "B.Fab")
		)
		(fp_line
			(start -0.2794 -0.1143)
			(end -0.2794 0.9144)
			(stroke
				(width 0.1)
				(type default)
			)
			(layer "B.Fab")
		)
		(pad "1" smd custom
			(at 0 0 90)
			(size 0.10414 0.10414)
			(layers "B.Cu" "B.Mask" "B.Paste")
			(net "PVNN_PCH_STBY")
			(options
				(clearance outline)
				(anchor circle)
			)
			(primitives
				(gr_poly
					(pts
						(xy -0.20828 -0.08636) (xy -0.20828 0.08636) (xy -0.08636 0.20828) (xy 0.086614 0.20828) (xy 0.20828 0.086614)
						(xy 0.20828 -0.08636) (xy 0.08636 -0.20828) (xy -0.08636 -0.20828)
					)
					(width 0)
					(fill yes)
				)
			)
		)
		(pad "2" smd custom
			(at 0 0.8001 90)
			(size 0.10414 0.10414)
			(layers "B.Cu" "B.Mask" "B.Paste")
			(net "GND")
			(options
				(clearance outline)
				(anchor circle)
			)
			(primitives
				(gr_poly
					(pts
						(xy -0.20828 -0.08636) (xy -0.20828 0.08636) (xy -0.08636 0.20828) (xy 0.086614 0.20828) (xy 0.20828 0.086614)
						(xy 0.20828 -0.08636) (xy 0.08636 -0.20828) (xy -0.08636 -0.20828)
					)
					(width 0)
					(fill yes)
				)
			)
		)
		(zone
			(layer "B.Cu")
			(hatch none 0.5)
			(connect_pads
				(clearance 0)
			)
			(min_thickness 0.25)
			(keepout
				(tracks allowed)
				(vias not_allowed)
				(pads allowed)
				(copperpour not_allowed)
				(footprints allowed)
			)
			(placement
				(enabled no)
				(sheetname "")
			)
			(fill
				(thermal_gap 0.5)
				(thermal_bridge_width 0.5)
				(island_removal_mode 0)
			)
			(polygon
				(pts
					(xy 385.24942 -112.0648) (xy 385.24942 -112.4458) (xy 385.42468 -112.4458) (xy 385.424934 -112.0648)
				)
			)
		)
		(zone
			(layer "B.Cu")
			(hatch none 0.5)
			(connect_pads
				(clearance 0)
			)
			(min_thickness 0.25)
			(keepout
				(tracks not_allowed)
				(vias allowed)
				(pads allowed)
				(copperpour not_allowed)
				(footprints allowed)
			)
			(placement
				(enabled no)
				(sheetname "")
			)
			(fill
				(thermal_gap 0.5)
				(thermal_bridge_width 0.5)
				(island_removal_mode 0)
			)
			(polygon
				(pts
					(xy 385.24942 -112.0648) (xy 385.24942 -112.4458) (xy 385.42468 -112.4458) (xy 385.424934 -112.0648)
				)
			)
		)
	)
)
